# BASEBOARD_FAB2 (Tioga Pass) — schematic netlist excerpt (pin names and nets, part order shuffled) for the footprints in the layout excerpt that follows; sources: Cadence DE-HDL packaged netlist, KiCad conversion of Wiwynn_Tioga_Pass_MB.brd

R9U3  RES  100.0 1% CHIP  pkg 0402  page 223 : A = PVCCIO_CPU1 ; B = SVID_DIO1_CPU1_R
C3P35  CAP  0.22UF 16V 10% X7R  pkg 0402  page 107 : A = P3E_CPU0_PE1_SS_TXP<6> ; B = P3E_CPU0_PE1_PCH_TXP<6>
R2U16  RES  0.0 5% CHIP  pkg 0402  page 107 : A = P3E_CPU0_PE1_SS_RXP<1> ; B = P3E_CPU0_PE1_SS_R_RXP<1>

(kicad_pcb
	(version 20260206)
	(generator "pcbnew")
	(generator_version "10.0")
	(general
		(thickness 1.6)
		(legacy_teardrops no)
	)
	(paper "A4")
	(title_block
		(title "Wiwynn_Tioga_Pass_MB.brd")
		(comment 1 "Tioga Pass / footprints 4686-4688 of 4770")
	)
	(layers
		(0 "F.Cu" signal "TOP")
		(4 "In1.Cu" signal "L2GND")
		(6 "In2.Cu" signal "L3")
		(8 "In3.Cu" signal "L4GND")
		(10 "In4.Cu" signal "L5")
		(12 "In5.Cu" signal "L6GND")
		(14 "In6.Cu" signal "L7VCC")
		(16 "In7.Cu" signal "L8VCC")
		(18 "In8.Cu" signal "L9GND")
		(20 "In9.Cu" signal "L10")
		(22 "In10.Cu" signal "L11GND")
		(24 "In11.Cu" signal "L12")
		(26 "In12.Cu" signal "L13GND")
		(2 "B.Cu" signal "BOTTOM")
		(9 "F.Adhes" user "F.Adhesive")
		(11 "B.Adhes" user "B.Adhesive")
		(13 "F.Paste" user "Package Geometry/Pastemask Top")
		(15 "B.Paste" user "Package Geometry/Pastemask Bottom")
		(5 "F.SilkS" user "Ref Des/Silkscreen Top")
		(7 "B.SilkS" user "Ref Des/Silkscreen Bottom")
		(1 "F.Mask" user "Board Geometry/Soldermask Top")
		(3 "B.Mask" user "Board Geometry/Soldermask Bottom")
		(17 "Dwgs.User" user "User.Drawings")
		(19 "Cmts.User" user "User.Comments")
		(21 "Eco1.User" user "User.Eco1")
		(23 "Eco2.User" user "User.Eco2")
		(25 "Edge.Cuts" user "Board Geometry/Outline")
		(27 "Margin" user)
		(31 "F.CrtYd" user "Package Geometry/Place Bound Top")
		(29 "B.CrtYd" user "Package Geometry/Place Bound Bottom")
		(35 "F.Fab" user "Ref Des/Assembly Top")
		(33 "B.Fab" user "Ref Des/Assembly Bottom")
	)
	(footprint ""
		(layer "B.Cu")
		(at 355.736398 -77.915516 180)
		(property "Reference" "C3P35"
			(at 0 0 0)
			(layer "B.SilkS")
			(hide yes)
			(effects
				(font
					(size 1.27 1.27)
				)
				(justify mirror)
			)
		)
		(property "Value" ""
			(at 0 0 0)
			(layer "B.Fab")
			(effects
				(font
					(size 1.27 1.27)
				)
				(justify mirror)
			)
		)
		(duplicate_pad_numbers_are_jumpers no)
		(fp_poly
			(pts
				(xy -0.3048 -0.1016) (xy -0.3048 0.9906) (xy 0.3048 0.9906) (xy 0.3048 -0.1016)
			)
			(stroke
				(width 0)
				(type default)
			)
			(fill no)
			(layer "B.CrtYd")
		)
		(fp_line
			(start 0.3048 0.9906)
			(end -0.3048 0.9906)
			(stroke
				(width 0.1)
				(type default)
			)
			(layer "B.Fab")
		)
		(fp_line
			(start 0.3048 -0.1016)
			(end 0.3048 0.9906)
			(stroke
				(width 0.1)
				(type default)
			)
			(layer "B.Fab")
		)
		(fp_line
			(start -0.3048 0.9906)
			(end -0.3048 -0.1016)
			(stroke
				(width 0.1)
				(type default)
			)
			(layer "B.Fab")
		)
		(fp_line
			(start -0.3048 -0.1016)
			(end 0.3048 -0.1016)
			(stroke
				(width 0.1)
				(type default)
			)
			(layer "B.Fab")
		)
		(pad "1" smd rect
			(at 0 0)
			(size 0.508 0.508)
			(layers "B.Cu" "B.Mask" "B.Paste")
			(net "P3E_CPU0_PE1_SS_TXP<6>")
		)
		(pad "2" smd rect
			(at 0 0.889)
			(size 0.508 0.508)
			(layers "B.Cu" "B.Mask" "B.Paste")
			(net "P3E_CPU0_PE1_PCH_TXP<6>")
		)
		(zone
			(layer "B.Cu")
			(hatch none 0.5)
			(connect_pads
				(clearance 0)
			)
			(min_thickness 0.25)
			(keepout
				(tracks not_allowed)
				(vias allowed)
				(pads allowed)
				(copperpour not_allowed)
				(footprints allowed)
			)
			(placement
				(enabled no)
				(sheetname "")
			)
			(fill
				(thermal_gap 0.5)
				(thermal_bridge_width 0.5)
				(island_removal_mode 0)
			)
			(polygon
				(pts
					(xy 355.482398 -78.550516) (xy 355.990398 -78.550516) (xy 355.990398 -78.169516) (xy 355.482398 -78.169516)
				)
			)
		)
		(zone
			(layer "B.Cu")
			(hatch none 0.5)
			(connect_pads
				(clearance 0)
			)
			(min_thickness 0.25)
			(keepout
				(tracks allowed)
				(vias not_allowed)
				(pads allowed)
				(copperpour not_allowed)
				(footprints allowed)
			)
			(placement
				(enabled no)
				(sheetname "")
			)
			(fill
				(thermal_gap 0.5)
				(thermal_bridge_width 0.5)
				(island_removal_mode 0)
			)
			(polygon
				(pts
					(xy 355.482398 -78.169516) (xy 355.990398 -78.169516) (xy 355.990398 -78.550516) (xy 355.482398 -78.550516)
				)
			)
		)
	)
	(footprint ""
		(layer "B.Cu")
		(at 336.140806 -60.368434)
		(property "Reference" "R2U16"
			(at 0 0 0)
			(layer "B.SilkS")
			(hide yes)
			(effects
				(font
					(size 1.27 1.27)
				)
				(justify mirror)
			)
		)
		(property "Value" ""
			(at 0 0 0)
			(layer "B.Fab")
			(effects
				(font
					(size 1.27 1.27)
				)
				(justify mirror)
			)
		)
		(duplicate_pad_numbers_are_jumpers no)
		(fp_poly
			(pts
				(xy 0.2794 -0.1016) (xy -0.2794 -0.1016) (xy -0.2794 0.9906) (xy 0.2794 0.9906)
			)
			(stroke
				(width 0)
				(type default)
			)
			(fill no)
			(layer "B.CrtYd")
		)
		(fp_line
			(start -0.2794 -0.1016)
			(end 0.2794 -0.1016)
			(stroke
				(width 0.1)
				(type default)
			)
			(layer "B.Fab")
		)
		(fp_line
			(start -0.2794 0.9906)
			(end -0.2794 -0.1016)
			(stroke
				(width 0.1)
				(type default)
			)
			(layer "B.Fab")
		)
		(fp_line
			(start 0.2794 -0.1016)
			(end 0.2794 0.9906)
			(stroke
				(width 0.1)
				(type default)
			)
			(layer "B.Fab")
		)
		(fp_line
			(start 0.2794 0.9906)
			(end -0.2794 0.9906)
			(stroke
				(width 0.1)
				(type default)
			)
			(layer "B.Fab")
		)
		(pad "1" smd rect
			(at 0 0 180)
			(size 0.508 0.508)
			(layers "B.Cu" "B.Mask" "B.Paste")
			(net "P3E_CPU0_PE1_SS_RXP<1>")
		)
		(pad "2" smd rect
			(at 0 0.889 180)
			(size 0.508 0.508)
			(layers "B.Cu" "B.Mask" "B.Paste")
			(net "P3E_CPU0_PE1_SS_R_RXP<1>")
		)
		(zone
			(layer "B.Cu")
			(hatch none 0.5)
			(connect_pads
				(clearance 0)
			)
			(min_thickness 0.25)
			(keepout
				(tracks allowed)
				(vias not_allowed)
				(pads allowed)
				(copperpour not_allowed)
				(footprints allowed)
			)
			(placement
				(enabled no)
				(sheetname "")
			)
			(fill
				(thermal_gap 0.5)
				(thermal_bridge_width 0.5)
				(island_removal_mode 0)
			)
			(polygon
				(pts
					(xy 336.394806 -60.114434) (xy 335.886806 -60.114434) (xy 335.886806 -59.733434) (xy 336.394806 -59.733434)
				)
			)
		)
		(zone
			(layer "B.Cu")
			(hatch none 0.5)
			(connect_pads
				(clearance 0)
			)
			(min_thickness 0.25)
			(keepout
				(tracks not_allowed)
				(vias allowed)
				(pads allowed)
				(copperpour not_allowed)
				(footprints allowed)
			)
			(placement
				(enabled no)
				(sheetname "")
			)
			(fill
				(thermal_gap 0.5)
				(thermal_bridge_width 0.5)
				(island_removal_mode 0)
			)
			(polygon
				(pts
					(xy 336.394806 -59.733434) (xy 335.886806 -59.733434) (xy 335.886806 -60.114434) (xy 336.394806 -60.114434)
				)
			)
		)
	)
	(footprint ""
		(layer "B.Cu")
		(at 10.551668 -3.321812 180)
		(property "Reference" "R9U3"
			(at 0 0 0)
			(layer "B.SilkS")
			(hide yes)
			(effects
				(font
					(size 1.27 1.27)
				)
				(justify mirror)
			)
		)
		(property "Value" ""
			(at 0 0 0)
			(layer "B.Fab")
			(effects
				(font
					(size 1.27 1.27)
				)
				(justify mirror)
			)
		)
		(duplicate_pad_numbers_are_jumpers no)
		(fp_rect
			(start 0.2794 0.9906)
			(end -0.2794 -0.1016)
			(stroke
				(width 0)
				(type default)
			)
			(fill no)
			(layer "B.CrtYd")
		)
		(fp_line
			(start 0.2794 0.9906)
			(end -0.2794 0.9906)
			(stroke
				(width 0.1)
				(type default)
			)
			(layer "B.Fab")
		)
		(fp_line
			(start 0.2794 -0.1016)
			(end 0.2794 0.9906)
			(stroke
				(width 0.1)
				(type default)
			)
			(layer "B.Fab")
		)
		(fp_line
			(start -0.2794 0.9906)
			(end -0.2794 -0.1016)
			(stroke
				(width 0.1)
				(type default)
			)
			(layer "B.Fab")
		)
		(fp_line
			(start -0.2794 -0.1016)
			(end 0.2794 -0.1016)
			(stroke
				(width 0.1)
				(type default)
			)
			(layer "B.Fab")
		)
		(pad "1" smd rect
			(at 0 0)
			(size 0.508 0.508)
			(layers "B.Cu" "B.Mask" "B.Paste")
			(net "PVCCIO_CPU1")
		)
		(pad "2" smd rect
			(at 0 0.889)
			(size 0.508 0.508)
			(layers "B.Cu" "B.Mask" "B.Paste")
			(net "SVID_DIO1_CPU1_R")
		)
		(zone
			(layer "B.Cu")
			(hatch none 0.5)
			(connect_pads
				(clearance 0)
			)
			(min_thickness 0.25)
			(keepout
				(tracks allowed)
				(vias not_allowed)
				(pads allowed)
				(copperpour not_allowed)
				(footprints allowed)
			)
			(placement
				(enabled no)
				(sheetname "")
			)
			(fill
				(thermal_gap 0.5)
				(thermal_bridge_width 0.5)
				(island_removal_mode 0)
			)
			(polygon
				(pts
					(xy 10.297668 -3.956812) (xy 10.297668 -3.575812) (xy 10.805668 -3.575812) (xy 10.805668 -3.956812)
				)
			)
		)
		(zone
			(layer "B.Cu")
			(hatch none 0.5)
			(connect_pads
				(clearance 0)
			)
			(min_thickness 0.25)
			(keepout
				(tracks not_allowed)
				(vias allowed)
				(pads allowed)
				(copperpour not_allowed)
				(footprints allowed)
			)
			(placement
				(enabled no)
				(sheetname "")
			)
			(fill
				(thermal_gap 0.5)
				(thermal_bridge_width 0.5)
				(island_removal_mode 0)
			)
			(polygon
				(pts
					(xy 10.297668 -3.956812) (xy 10.297668 -3.575812) (xy 10.805668 -3.575812) (xy 10.805668 -3.956812)
				)
			)
		)
	)
)
